(kicad_pcb
	(version 20260206)
	(generator "pcbnew")
	(generator_version "10.0")
	(general
		(thickness 1.6)
		(legacy_teardrops no)
	)
	(paper "A4")
	(title_block
		(title "04192023_DAF0TMB3IC0_F0TG_MB_C_brd_V02_OCP.brd")
		(comment 1 "Grand Teton / footprints 1953-1959 of 8354")
	)
	(layers
		(0 "F.Cu" signal "TOP")
		(4 "In1.Cu" signal "GND")
		(6 "In2.Cu" signal "IN1")
		(8 "In3.Cu" signal "GND1")
		(10 "In4.Cu" signal "IN2")
		(12 "In5.Cu" signal "GND2")
		(14 "In6.Cu" signal "IN3")
		(16 "In7.Cu" signal "GND3")
		(18 "In8.Cu" signal "VCC")
		(20 "In9.Cu" signal "VCC1")
		(22 "In10.Cu" signal "GND4")
		(24 "In11.Cu" signal "IN4")
		(26 "In12.Cu" signal "GND5")
		(28 "In13.Cu" signal "IN5")
		(30 "In14.Cu" signal "GND6")
		(32 "In15.Cu" signal "IN6")
		(34 "In16.Cu" signal "GND7")
		(2 "B.Cu" signal "BOTTOM")
		(9 "F.Adhes" user "F.Adhesive")
		(11 "B.Adhes" user "B.Adhesive")
		(13 "F.Paste" user "Package Geometry/Pastemask Top")
		(15 "B.Paste" user "Package Geometry/Pastemask Bottom")
		(5 "F.SilkS" user "Ref Des/Silkscreen Top")
		(7 "B.SilkS" user "Ref Des/Silkscreen Bottom")
		(1 "F.Mask" user "Board Geometry/Soldermask Top")
		(3 "B.Mask" user "Board Geometry/Soldermask Bottom")
		(17 "Dwgs.User" user "User.Drawings")
		(19 "Cmts.User" user "User.Comments")
		(21 "Eco1.User" user "User.Eco1")
		(23 "Eco2.User" user "User.Eco2")
		(25 "Edge.Cuts" user "Board Geometry/Outline")
		(27 "Margin" user)
		(31 "F.CrtYd" user "Package Geometry/Place Bound Top")
		(29 "B.CrtYd" user "Package Geometry/Place Bound Bottom")
		(35 "F.Fab" user "Ref Des/Assembly Top")
		(33 "B.Fab" user "Ref Des/Assembly Bottom")
	)
	(footprint ""
		(layer "F.Cu")
		(at 426.673264 -423.621962 90)
		(property "Reference" "R6250"
			(at 0 0 90)
			(layer "F.SilkS")
			(hide yes)
			(effects
				(font
					(size 1.27 1.27)
				)
			)
		)
		(property "Value" ""
			(at 0 0 90)
			(layer "F.Fab")
			(effects
				(font
					(size 1.27 1.27)
				)
			)
		)
		(duplicate_pad_numbers_are_jumpers no)
		(fp_line
			(start 0.7874 -0.4064)
			(end 0.7874 0.4064)
			(stroke
				(width 0.1524)
				(type default)
			)
			(layer "F.SilkS")
		)
		(fp_line
			(start -0.7874 -0.4064)
			(end 0.7874 -0.4064)
			(stroke
				(width 0.1524)
				(type default)
			)
			(layer "F.SilkS")
		)
		(fp_line
			(start 0.7874 0.4064)
			(end -0.7874 0.4064)
			(stroke
				(width 0.1524)
				(type default)
			)
			(layer "F.SilkS")
		)
		(fp_line
			(start -0.7874 0.4064)
			(end -0.7874 -0.4064)
			(stroke
				(width 0.1524)
				(type default)
			)
			(layer "F.SilkS")
		)
		(fp_line
			(start -0.12065 -0.305054)
			(end -0.12065 -0.2794)
			(stroke
				(width 0.1)
				(type default)
			)
			(layer "F.Fab")
		)
		(fp_line
			(start -0.67945 -0.305054)
			(end -0.12065 -0.305054)
			(stroke
				(width 0.1)
				(type default)
			)
			(layer "F.Fab")
		)
		(fp_line
			(start 0.67945 -0.3048)
			(end 0.67945 0.3048)
			(stroke
				(width 0.1)
				(type default)
			)
			(layer "F.Fab")
		)
		(fp_line
			(start 0.12065 -0.3048)
			(end 0.67945 -0.3048)
			(stroke
				(width 0.1)
				(type default)
			)
			(layer "F.Fab")
		)
		(fp_line
			(start 0.12065 -0.2794)
			(end 0.12065 -0.3048)
			(stroke
				(width 0.1)
				(type default)
			)
			(layer "F.Fab")
		)
		(fp_line
			(start -0.12065 -0.2794)
			(end 0.12065 -0.2794)
			(stroke
				(width 0.1)
				(type default)
			)
			(layer "F.Fab")
		)
		(fp_line
			(start 0.120396 0.2794)
			(end -0.12065 0.2794)
			(stroke
				(width 0.1)
				(type default)
			)
			(layer "F.Fab")
		)
		(fp_line
			(start -0.12065 0.2794)
			(end -0.12065 0.3048)
			(stroke
				(width 0.1)
				(type default)
			)
			(layer "F.Fab")
		)
		(fp_line
			(start 0.67945 0.3048)
			(end 0.120396 0.3048)
			(stroke
				(width 0.1)
				(type default)
			)
			(layer "F.Fab")
		)
		(fp_line
			(start 0.120396 0.3048)
			(end 0.120396 0.2794)
			(stroke
				(width 0.1)
				(type default)
			)
			(layer "F.Fab")
		)
		(fp_line
			(start -0.12065 0.3048)
			(end -0.67945 0.3048)
			(stroke
				(width 0.1)
				(type default)
			)
			(layer "F.Fab")
		)
		(fp_line
			(start -0.67945 0.3048)
			(end -0.67945 -0.305054)
			(stroke
				(width 0.1)
				(type default)
			)
			(layer "F.Fab")
		)
		(pad "1" smd circle
			(at -0.40005 0 90)
			(size 0 0)
			(layers "F.Cu" "F.Mask" "F.Paste")
			(net "GND")
		)
		(pad "2" smd circle
			(at 0.40005 0 90)
			(size 0 0)
			(layers "F.Cu" "F.Mask" "F.Paste")
			(net "HSC_TYPE_ADC_A1")
		)
	)
	(footprint ""
		(layer "F.Cu")
		(at 141.29512 -30.82671 90)
		(property "Reference" "C6017"
			(at 0 0 90)
			(layer "F.SilkS")
			(hide yes)
			(effects
				(font
					(size 1.27 1.27)
				)
			)
		)
		(property "Value" ""
			(at 0 0 90)
			(layer "F.Fab")
			(effects
				(font
					(size 1.27 1.27)
				)
			)
		)
		(duplicate_pad_numbers_are_jumpers no)
		(fp_line
			(start 0.7874 -0.4064)
			(end 0.7874 0.4064)
			(stroke
				(width 0.1524)
				(type default)
			)
			(layer "F.SilkS")
		)
		(fp_line
			(start -0.7874 -0.4064)
			(end 0.7874 -0.4064)
			(stroke
				(width 0.1524)
				(type default)
			)
			(layer "F.SilkS")
		)
		(fp_line
			(start 0.7874 0.4064)
			(end -0.7874 0.4064)
			(stroke
				(width 0.1524)
				(type default)
			)
			(layer "F.SilkS")
		)
		(fp_line
			(start -0.7874 0.4064)
			(end -0.7874 -0.4064)
			(stroke
				(width 0.1524)
				(type default)
			)
			(layer "F.SilkS")
		)
		(fp_line
			(start 0.6858 -0.3048)
			(end 0.6858 0.3048)
			(stroke
				(width 0.1)
				(type default)
			)
			(layer "F.Fab")
		)
		(fp_line
			(start 0.1016 -0.3048)
			(end 0.6858 -0.3048)
			(stroke
				(width 0.1)
				(type default)
			)
			(layer "F.Fab")
		)
		(fp_line
			(start -0.1016 -0.3048)
			(end -0.1016 -0.2794)
			(stroke
				(width 0.1)
				(type default)
			)
			(layer "F.Fab")
		)
		(fp_line
			(start -0.6858 -0.3048)
			(end -0.1016 -0.3048)
			(stroke
				(width 0.1)
				(type default)
			)
			(layer "F.Fab")
		)
		(fp_line
			(start 0.1016 -0.2794)
			(end 0.1016 -0.3048)
			(stroke
				(width 0.1)
				(type default)
			)
			(layer "F.Fab")
		)
		(fp_line
			(start -0.1016 -0.2794)
			(end 0.1016 -0.2794)
			(stroke
				(width 0.1)
				(type default)
			)
			(layer "F.Fab")
		)
		(fp_line
			(start 0.1016 0.2794)
			(end -0.1016 0.2794)
			(stroke
				(width 0.1)
				(type default)
			)
			(layer "F.Fab")
		)
		(fp_line
			(start -0.1016 0.2794)
			(end -0.1016 0.3048)
			(stroke
				(width 0.1)
				(type default)
			)
			(layer "F.Fab")
		)
		(fp_line
			(start 0.6858 0.3048)
			(end 0.1016 0.3048)
			(stroke
				(width 0.1)
				(type default)
			)
			(layer "F.Fab")
		)
		(fp_line
			(start 0.1016 0.3048)
			(end 0.1016 0.2794)
			(stroke
				(width 0.1)
				(type default)
			)
			(layer "F.Fab")
		)
		(fp_line
			(start -0.1016 0.3048)
			(end -0.6858 0.3048)
			(stroke
				(width 0.1)
				(type default)
			)
			(layer "F.Fab")
		)
		(fp_line
			(start -0.6858 0.3048)
			(end -0.6858 -0.3048)
			(stroke
				(width 0.1)
				(type default)
			)
			(layer "F.Fab")
		)
		(pad "1" smd rect
			(at -0.40005 0 270)
			(size 0.4572 0.508)
			(layers "F.Cu" "F.Mask" "F.Paste")
			(net "USB3_CPU0_BMC_RX_HUB2_DP")
		)
		(pad "2" smd rect
			(at 0.40005 0 270)
			(size 0.4572 0.508)
			(layers "F.Cu" "F.Mask" "F.Paste")
			(net "USB3_CPU0_BMC_RX_HUB_C_DP")
		)
	)
	(footprint ""
		(layer "F.Cu")
		(at 308.813962 -337.399122)
		(property "Reference" "PL13"
			(at -6.299962 -15.126208 0)
			(unlocked yes)
			(layer "F.SilkS")
			(effects
				(font
					(size 0.7874 0.5842)
					(thickness 0.1524)
				)
				(justify left)
			)
		)
		(property "Value" ""
			(at 0 0 0)
			(layer "F.Fab")
			(effects
				(font
					(size 1.27 1.27)
				)
			)
		)
		(duplicate_pad_numbers_are_jumpers no)
		(fp_line
			(start -3.750056 -5.500116)
			(end -2.393442 -5.500116)
			(stroke
				(width 0.1524)
				(type default)
			)
			(layer "F.SilkS")
		)
		(fp_line
			(start -3.750056 5.500116)
			(end -3.750056 -5.500116)
			(stroke
				(width 0.1524)
				(type default)
			)
			(layer "F.SilkS")
		)
		(fp_line
			(start -2.393442 5.500116)
			(end -3.750056 5.500116)
			(stroke
				(width 0.1524)
				(type default)
			)
			(layer "F.SilkS")
		)
		(fp_line
			(start 2.393442 5.500116)
			(end 3.750056 5.500116)
			(stroke
				(width 0.1524)
				(type default)
			)
			(layer "F.SilkS")
		)
		(fp_line
			(start 3.750056 -5.500116)
			(end 2.393442 -5.500116)
			(stroke
				(width 0.1524)
				(type default)
			)
			(layer "F.SilkS")
		)
		(fp_line
			(start 3.750056 5.500116)
			(end 3.750056 -5.500116)
			(stroke
				(width 0.1524)
				(type default)
			)
			(layer "F.SilkS")
		)
		(fp_poly
			(pts
				(xy -3.9116 -4.249928) (xy -4.3434 -4.034028) (xy -4.3434 -4.465828)
			)
			(stroke
				(width 0)
				(type default)
			)
			(fill yes)
			(layer "F.SilkS")
		)
		(fp_line
			(start -3.750056 -5.500116)
			(end -3.750056 5.500116)
			(stroke
				(width 0.1)
				(type default)
			)
			(layer "F.Fab")
		)
		(fp_line
			(start -3.750056 5.500116)
			(end 3.750056 5.500116)
			(stroke
				(width 0.1)
				(type default)
			)
			(layer "F.Fab")
		)
		(fp_line
			(start 3.750056 -5.500116)
			(end -3.750056 -5.500116)
			(stroke
				(width 0.1)
				(type default)
			)
			(layer "F.Fab")
		)
		(fp_line
			(start 3.750056 5.500116)
			(end 3.750056 -5.500116)
			(stroke
				(width 0.1)
				(type default)
			)
			(layer "F.Fab")
		)
		(fp_poly
			(pts
				(xy -4.9276 -4.757928) (xy -4.9276 -3.741928) (xy -3.9116 -4.249928)
			)
			(stroke
				(width 0)
				(type default)
			)
			(fill yes)
			(layer "F.Fab")
		)
		(pad "1" smd rect
			(at 0 -4.249928 270)
			(size 2.413 4.5212)
			(layers "F.Cu" "F.Mask" "F.Paste")
			(net "SW_PVDDCR_CPU1_P0_SW4")
		)
		(pad "2" smd rect
			(at 0 -1.175004 270)
			(size 1.3716 4.5212)
			(layers "F.Cu" "F.Mask" "F.Paste")
			(net "IND_CPU1_P0_CPL3")
		)
		(pad "3" smd rect
			(at 0 1.175004 270)
			(size 1.3716 4.5212)
			(layers "F.Cu" "F.Mask" "F.Paste")
			(net "GND")
		)
		(pad "4" smd rect
			(at 0 4.249928 270)
			(size 2.413 4.5212)
			(layers "F.Cu" "F.Mask" "F.Paste")
			(net "PVDDCR_CPU1_P0")
		)
	)
	(footprint ""
		(layer "F.Cu")
		(at 21.176996 -98.171508)
		(property "Reference" "R3665"
			(at 0 0 0)
			(layer "F.SilkS")
			(hide yes)
			(effects
				(font
					(size 1.27 1.27)
				)
			)
		)
		(property "Value" ""
			(at 0 0 0)
			(layer "F.Fab")
			(effects
				(font
					(size 1.27 1.27)
				)
			)
		)
		(duplicate_pad_numbers_are_jumpers no)
		(fp_line
			(start -0.7874 -0.4064)
			(end 0.7874 -0.4064)
			(stroke
				(width 0.1524)
				(type default)
			)
			(layer "F.SilkS")
		)
		(fp_line
			(start -0.7874 0.4064)
			(end -0.7874 -0.4064)
			(stroke
				(width 0.1524)
				(type default)
			)
			(layer "F.SilkS")
		)
		(fp_line
			(start 0.7874 -0.4064)
			(end 0.7874 0.4064)
			(stroke
				(width 0.1524)
				(type default)
			)
			(layer "F.SilkS")
		)
		(fp_line
			(start 0.7874 0.4064)
			(end -0.7874 0.4064)
			(stroke
				(width 0.1524)
				(type default)
			)
			(layer "F.SilkS")
		)
		(fp_line
			(start -0.67945 -0.305054)
			(end -0.12065 -0.305054)
			(stroke
				(width 0.1)
				(type default)
			)
			(layer "F.Fab")
		)
		(fp_line
			(start -0.67945 0.3048)
			(end -0.67945 -0.305054)
			(stroke
				(width 0.1)
				(type default)
			)
			(layer "F.Fab")
		)
		(fp_line
			(start -0.12065 -0.305054)
			(end -0.12065 -0.2794)
			(stroke
				(width 0.1)
				(type default)
			)
			(layer "F.Fab")
		)
		(fp_line
			(start -0.12065 -0.2794)
			(end 0.12065 -0.2794)
			(stroke
				(width 0.1)
				(type default)
			)
			(layer "F.Fab")
		)
		(fp_line
			(start -0.12065 0.2794)
			(end -0.12065 0.3048)
			(stroke
				(width 0.1)
				(type default)
			)
			(layer "F.Fab")
		)
		(fp_line
			(start -0.12065 0.3048)
			(end -0.67945 0.3048)
			(stroke
				(width 0.1)
				(type default)
			)
			(layer "F.Fab")
		)
		(fp_line
			(start 0.120396 0.2794)
			(end -0.12065 0.2794)
			(stroke
				(width 0.1)
				(type default)
			)
			(layer "F.Fab")
		)
		(fp_line
			(start 0.120396 0.3048)
			(end 0.120396 0.2794)
			(stroke
				(width 0.1)
				(type default)
			)
			(layer "F.Fab")
		)
		(fp_line
			(start 0.12065 -0.3048)
			(end 0.67945 -0.3048)
			(stroke
				(width 0.1)
				(type default)
			)
			(layer "F.Fab")
		)
		(fp_line
			(start 0.12065 -0.2794)
			(end 0.12065 -0.3048)
			(stroke
				(width 0.1)
				(type default)
			)
			(layer "F.Fab")
		)
		(fp_line
			(start 0.67945 -0.3048)
			(end 0.67945 0.3048)
			(stroke
				(width 0.1)
				(type default)
			)
			(layer "F.Fab")
		)
		(fp_line
			(start 0.67945 0.3048)
			(end 0.120396 0.3048)
			(stroke
				(width 0.1)
				(type default)
			)
			(layer "F.Fab")
		)
		(pad "1" smd circle
			(at -0.40005 0)
			(size 0 0)
			(layers "F.Cu" "F.Mask" "F.Paste")
			(net "USB_HUB_PGANG")
		)
		(pad "2" smd circle
			(at 0.40005 0)
			(size 0 0)
			(layers "F.Cu" "F.Mask" "F.Paste")
			(net "GND")
		)
	)
	(footprint ""
		(layer "F.Cu")
		(at 395.595348 -16.100298 90)
		(property "Reference" "C1552"
			(at 0 0 90)
			(layer "F.SilkS")
			(hide yes)
			(effects
				(font
					(size 1.27 1.27)
				)
			)
		)
		(property "Value" ""
			(at 0 0 90)
			(layer "F.Fab")
			(effects
				(font
					(size 1.27 1.27)
				)
			)
		)
		(duplicate_pad_numbers_are_jumpers no)
		(fp_line
			(start 0.299974 -0.150114)
			(end 0.299974 0.150114)
			(stroke
				(width 0.1)
				(type default)
			)
			(layer "F.Fab")
		)
		(fp_line
			(start -0.299974 -0.150114)
			(end 0.299974 -0.150114)
			(stroke
				(width 0.1)
				(type default)
			)
			(layer "F.Fab")
		)
		(fp_line
			(start 0.299974 0.150114)
			(end -0.299974 0.150114)
			(stroke
				(width 0.1)
				(type default)
			)
			(layer "F.Fab")
		)
		(fp_line
			(start -0.299974 0.150114)
			(end -0.299974 -0.150114)
			(stroke
				(width 0.1)
				(type default)
			)
			(layer "F.Fab")
		)
		(pad "1" smd rect
			(at -0.2667 0 90)
			(size 0.3048 0.381)
			(layers "F.Cu" "F.Mask" "F.Paste")
			(net "P5E_CPU0_G3_TX_C_DN<13>")
		)
		(pad "2" smd rect
			(at 0.2667 0 90)
			(size 0.3048 0.381)
			(layers "F.Cu" "F.Mask" "F.Paste")
			(net "P5E_CPU0_G3_TX_DN<13>")
		)
	)
	(footprint ""
		(layer "F.Cu")
		(at 42.527982 -386.951474)
		(property "Reference" "R609"
			(at 0 0 0)
			(layer "F.SilkS")
			(hide yes)
			(effects
				(font
					(size 1.27 1.27)
				)
			)
		)
		(property "Value" ""
			(at 0 0 0)
			(layer "F.Fab")
			(effects
				(font
					(size 1.27 1.27)
				)
			)
		)
		(duplicate_pad_numbers_are_jumpers no)
		(fp_line
			(start -0.32512 -0.175006)
			(end 0.32512 -0.175006)
			(stroke
				(width 0.1)
				(type default)
			)
			(layer "F.Fab")
		)
		(fp_line
			(start -0.32512 0.175006)
			(end -0.32512 -0.175006)
			(stroke
				(width 0.1)
				(type default)
			)
			(layer "F.Fab")
		)
		(fp_line
			(start 0.32512 -0.175006)
			(end 0.32512 0.175006)
			(stroke
				(width 0.1)
				(type default)
			)
			(layer "F.Fab")
		)
		(fp_line
			(start 0.32512 0.175006)
			(end -0.32512 0.175006)
			(stroke
				(width 0.1)
				(type default)
			)
			(layer "F.Fab")
		)
		(pad "1" smd rect
			(at -0.2667 0)
			(size 0.3048 0.381)
			(layers "F.Cu" "F.Mask" "F.Paste")
			(net "CLK_100M_RETIMER_CPU1_P0_R_DN")
		)
		(pad "2" smd rect
			(at 0.2667 0 180)
			(size 0.3048 0.381)
			(layers "F.Cu" "F.Mask" "F.Paste")
			(net "CLK_100M_RETIMER_CPU1_P0_DN")
		)
	)
	(footprint ""
		(layer "F.Cu")
		(at 171.269406 -125.751336 180)
		(property "Reference" "R6144"
			(at 0 0 180)
			(layer "F.SilkS")
			(hide yes)
			(effects
				(font
					(size 1.27 1.27)
				)
			)
		)
		(property "Value" ""
			(at 0 0 180)
			(layer "F.Fab")
			(effects
				(font
					(size 1.27 1.27)
				)
			)
		)
		(duplicate_pad_numbers_are_jumpers no)
		(fp_line
			(start 0.7874 0.4064)
			(end -0.7874 0.4064)
			(stroke
				(width 0.1524)
				(type default)
			)
			(layer "F.SilkS")
		)
		(fp_line
			(start 0.7874 -0.4064)
			(end 0.7874 0.4064)
			(stroke
				(width 0.1524)
				(type default)
			)
			(layer "F.SilkS")
		)
		(fp_line
			(start -0.7874 0.4064)
			(end -0.7874 -0.4064)
			(stroke
				(width 0.1524)
				(type default)
			)
			(layer "F.SilkS")
		)
		(fp_line
			(start -0.7874 -0.4064)
			(end 0.7874 -0.4064)
			(stroke
				(width 0.1524)
				(type default)
			)
			(layer "F.SilkS")
		)
		(fp_line
			(start 0.67945 0.3048)
			(end 0.120396 0.3048)
			(stroke
				(width 0.1)
				(type default)
			)
			(layer "F.Fab")
		)
		(fp_line
			(start 0.67945 -0.3048)
			(end 0.67945 0.3048)
			(stroke
				(width 0.1)
				(type default)
			)
			(layer "F.Fab")
		)
		(fp_line
			(start 0.12065 -0.2794)
			(end 0.12065 -0.3048)
			(stroke
				(width 0.1)
				(type default)
			)
			(layer "F.Fab")
		)
		(fp_line
			(start 0.12065 -0.3048)
			(end 0.67945 -0.3048)
			(stroke
				(width 0.1)
				(type default)
			)
			(layer "F.Fab")
		)
		(fp_line
			(start 0.120396 0.3048)
			(end 0.120396 0.2794)
			(stroke
				(width 0.1)
				(type default)
			)
			(layer "F.Fab")
		)
		(fp_line
			(start 0.120396 0.2794)
			(end -0.12065 0.2794)
			(stroke
				(width 0.1)
				(type default)
			)
			(layer "F.Fab")
		)
		(fp_line
			(start -0.12065 0.3048)
			(end -0.67945 0.3048)
			(stroke
				(width 0.1)
				(type default)
			)
			(layer "F.Fab")
		)
		(fp_line
			(start -0.12065 0.2794)
			(end -0.12065 0.3048)
			(stroke
				(width 0.1)
				(type default)
			)
			(layer "F.Fab")
		)
		(fp_line
			(start -0.12065 -0.2794)
			(end 0.12065 -0.2794)
			(stroke
				(width 0.1)
				(type default)
			)
			(layer "F.Fab")
		)
		(fp_line
			(start -0.12065 -0.305054)
			(end -0.12065 -0.2794)
			(stroke
				(width 0.1)
				(type default)
			)
			(layer "F.Fab")
		)
		(fp_line
			(start -0.67945 0.3048)
			(end -0.67945 -0.305054)
			(stroke
				(width 0.1)
				(type default)
			)
			(layer "F.Fab")
		)
		(fp_line
			(start -0.67945 -0.305054)
			(end -0.12065 -0.305054)
			(stroke
				(width 0.1)
				(type default)
			)
			(layer "F.Fab")
		)
		(pad "1" smd circle
			(at -0.40005 0 180)
			(size 0 0)
			(layers "F.Cu" "F.Mask" "F.Paste")
			(net "FM_BOARD_BMC_SKU_ID1")
		)
		(pad "2" smd circle
			(at 0.40005 0 180)
			(size 0 0)
			(layers "F.Cu" "F.Mask" "F.Paste")
			(net "GND")
		)
	)
)
